FILE_TYPE = CONNECTIVITY;
{Allegro Design Entry HDL 16.6-p007 (v16-6-112F) 10/10/2012}
"PAGE_NUMBER" = 98;
0"NC";
1"PVDDQ_ABC\g";
2"PVDDQ_DEF\g";
3"GND\g";
4"PVDDQ_ABC\g";
5"GND\g";
6"PVDDQ_ABC\g";
7"GND\g";
8"GND\g";
9"GND\g";
10"GND\g";
11"PVDDQ_DEF\g";
12"PVDDQ_DEF\g";
13"M_D_CPU_VREF";
14"M_A_CPU_VREF";
15"M_D_VREF";
16"M_A_VREF";
17"M_E_CPU_VREF";
18"M_B_CPU_VREF";
19"M_E_VREF";
20"M_B_VREF";
21"M_F_CPU_VREF";
22"M_C_CPU_VREF";
23"M_F_VREF";
24"M_C_VREF";
%"PVDDQ_ABC"
"1","(-1800,4600)","0","mstr_symbols","I1";
;
HDL_POWER"PVDDQ_ABC"
BODY_TYPE"PLUMBING"
CDS_LIB"mstr_symbols"
VOLTAGE"1.2V";
"G\NAC"1;
%"PVDDQ_DEF"
"1","(-1800,2925)","0","mstr_symbols","I10";
;
HDL_POWER"PVDDQ_DEF"
BODY_TYPE"PLUMBING"
CDS_LIB"mstr_symbols"
VOLTAGE"1.2V";
"G\NAC"2;
%"RES"
"2","(-1725,2025)","2","mstr_discrete","I12";
;
CDS_SEC"1"
ROOM"PROC"
CDS_LOCATION"R6L16"
SEC"1"
SEC_TYPE"0402"
BOM_COST"PROC_SOCKET"
CDS_LIB"mstr_discrete"
WATTAGE"1/16W"
MATERIAL"CHIP"
PACK_TYPE"0402"
TOLERANCE"1%"
VALUE"1.00K"
PART_NUMBER"G21796-026"
LOCATION"R6L16";
"A"
$PN"1"15;
"B"
$PN"2"3;
%"GND"
"1","(-2025,1700)","0","mstr_symbols","I13";
;
HDL_POWER"GND"
BODY_TYPE"PLUMBING"
SIZE"1B"
CDS_LIB"mstr_symbols"
VOLTAGE"0";
"A\NAC"3;
%"RES"
"1","(-2025,2350)","0","mstr_discrete","I14";
;
CDS_SEC"1"
ROOM"PROC"
CDS_LOCATION"R6M2"
SEC"1"
SEC_TYPE"0402"
BOM_COST"PROC_SOCKET"
CDS_LIB"mstr_discrete"
WATTAGE"1/16W"
MATERIAL"CHIP"
PACK_TYPE"0402"
TOLERANCE"1.0%"
VALUE"2"
PART_NUMBER"G21796-274"
LOCATION"R6M2";
"B"
$PN"2"15;
"A"
$PN"1"13;
%"CAP_A"
"1","(-2250,2050)","0","dev_discrete","I33";
;
ROOM"MEM"
SEC"1"
SEC_TYPE"0402V"
CDS_SEC"1"
CDS_LIB"dev_discrete"
BOM_COST"SM_CONTROLLER"
CDS_LOCATION"C6M2"
MATERIAL"X7R"
VOLTAGE"25V"
PACK_TYPE"0402V"
TOLERANCE"10%"
VALUE"0.01UF"
PART_NUMBER"A36096-045"
LOCATION"C6M2";
"B"
$PN"2"3;
"A"
$PN"1"13;
%"RES"
"2","(-1800,4350)","2","mstr_discrete","I36";
;
CDS_SEC"1"
ROOM"MEM"
CDS_LOCATION"R4F4"
SEC"1"
BOM_COST"SM_CONTROLLER"
CDS_LIB"mstr_discrete"
SEC_TYPE"0402"
WATTAGE"1/16W"
MATERIAL"CHIP"
PACK_TYPE"0402"
TOLERANCE"1%"
VALUE"1.00K"
PART_NUMBER"G21796-026"
LOCATION"R4F4";
"A"
$PN"1"1;
"B"
$PN"2"16;
%"PVDDQ_ABC"
"1","(250,4600)","0","mstr_symbols","I37";
;
HDL_POWER"PVDDQ_ABC"
BODY_TYPE"PLUMBING"
CDS_LIB"mstr_symbols"
VOLTAGE"1.2V";
"G\NAC"4;
%"RES"
"2","(250,4350)","2","mstr_discrete","I38";
;
CDS_SEC"1"
ROOM"MEM"
CDS_LOCATION"R4G2"
SEC"1"
SEC_TYPE"0402"
CDS_LIB"mstr_discrete"
BOM_COST"SM_CONTROLLER"
WATTAGE"1/16W"
MATERIAL"CHIP"
PACK_TYPE"0402"
TOLERANCE"1%"
VALUE"1.00K"
PART_NUMBER"G21796-026"
LOCATION"R4G2";
"A"
$PN"1"4;
"B"
$PN"2"20;
%"RES"
"2","(-1725,3700)","2","mstr_discrete","I4";
;
CDS_SEC"1"
ROOM"PROC"
CDS_LOCATION"R4F5"
SEC"1"
CDS_LIB"mstr_discrete"
BOM_COST"PROC_SOCKET"
SEC_TYPE"0402"
WATTAGE"1/16W"
MATERIAL"CHIP"
PACK_TYPE"0402"
TOLERANCE"1%"
VALUE"1.00K"
PART_NUMBER"G21796-026"
LOCATION"R4F5";
"A"
$PN"1"16;
"B"
$PN"2"9;
%"RES"
"2","(325,3700)","2","mstr_discrete","I40";
;
CDS_SEC"1"
ROOM"PROC"
CDS_LOCATION"R4G3"
SEC"1"
SEC_TYPE"0402"
BOM_COST"PROC_SOCKET"
CDS_LIB"mstr_discrete"
WATTAGE"1/16W"
MATERIAL"CHIP"
PACK_TYPE"0402"
TOLERANCE"1%"
VALUE"1.00K"
PART_NUMBER"G21796-026"
LOCATION"R4G3";
"A"
$PN"1"20;
"B"
$PN"2"5;
%"GND"
"1","(25,3375)","0","mstr_symbols","I41";
;
HDL_POWER"GND"
BODY_TYPE"PLUMBING"
CDS_LIB"mstr_symbols"
SIZE"1B"
VOLTAGE"0";
"A\NAC"5;
%"RES"
"1","(25,4025)","0","mstr_discrete","I42";
;
CDS_SEC"1"
ROOM"PROC"
CDS_LOCATION"R4G1"
SEC"1"
SEC_TYPE"0402"
BOM_COST"PROC_SOCKET"
CDS_LIB"mstr_discrete"
WATTAGE"1/16W"
MATERIAL"CHIP"
PACK_TYPE"0402"
TOLERANCE"1.0%"
VALUE"2"
PART_NUMBER"G21796-274"
LOCATION"R4G1";
"B"
$PN"2"20;
"A"
$PN"1"18;
%"CAP_A"
"1","(-200,3725)","0","dev_discrete","I43";
;
ROOM"MEM"
SEC"1"
SEC_TYPE"0402V"
CDS_SEC"1"
CDS_LIB"dev_discrete"
BOM_COST"SM_CONTROLLER"
CDS_LOCATION"C4G1"
MATERIAL"X7R"
VOLTAGE"25V"
PACK_TYPE"0402V"
TOLERANCE"10%"
VALUE"0.01UF"
PART_NUMBER"A36096-045"
LOCATION"C4G1";
"B"
$PN"2"5;
"A"
$PN"1"18;
%"PVDDQ_ABC"
"1","(2400,4600)","0","mstr_symbols","I45";
;
HDL_POWER"PVDDQ_ABC"
BODY_TYPE"PLUMBING"
CDS_LIB"mstr_symbols"
VOLTAGE"1.2V";
"G\NAC"6;
%"RES"
"2","(2400,4350)","2","mstr_discrete","I46";
;
CDS_SEC"1"
ROOM"MEM"
CDS_LOCATION"R4G21"
SEC"1"
SEC_TYPE"0402"
CDS_LIB"mstr_discrete"
BOM_COST"SM_CONTROLLER"
WATTAGE"1/16W"
MATERIAL"CHIP"
PACK_TYPE"0402"
TOLERANCE"1%"
VALUE"1.00K"
PART_NUMBER"G21796-026"
LOCATION"R4G21";
"A"
$PN"1"6;
"B"
$PN"2"24;
%"RES"
"2","(2475,3700)","2","mstr_discrete","I48";
;
CDS_SEC"1"
ROOM"PROC"
CDS_LOCATION"R4G22"
SEC"1"
SEC_TYPE"0402"
BOM_COST"PROC_SOCKET"
CDS_LIB"mstr_discrete"
WATTAGE"1/16W"
MATERIAL"CHIP"
PACK_TYPE"0402"
TOLERANCE"1%"
VALUE"1.00K"
PART_NUMBER"G21796-026"
LOCATION"R4G22";
"A"
$PN"1"24;
"B"
$PN"2"7;
%"GND"
"1","(2175,3375)","0","mstr_symbols","I49";
;
HDL_POWER"GND"
BODY_TYPE"PLUMBING"
CDS_LIB"mstr_symbols"
SIZE"1B"
VOLTAGE"0";
"A\NAC"7;
%"RES"
"1","(-2025,4025)","0","mstr_discrete","I5";
;
CDS_SEC"1"
ROOM"PROC"
CDS_LOCATION"R4F3"
SEC"1"
CDS_LIB"mstr_discrete"
BOM_COST"PROC_SOCKET"
SEC_TYPE"0402"
WATTAGE"1/16W"
MATERIAL"CHIP"
PACK_TYPE"0402"
TOLERANCE"1.0%"
VALUE"2"
PART_NUMBER"G21796-274"
LOCATION"R4F3";
"B"
$PN"2"16;
"A"
$PN"1"14;
%"RES"
"1","(2175,4025)","0","mstr_discrete","I50";
;
CDS_SEC"1"
ROOM"PROC"
CDS_LOCATION"R4G20"
SEC"1"
SEC_TYPE"0402"
BOM_COST"PROC_SOCKET"
CDS_LIB"mstr_discrete"
WATTAGE"1/16W"
MATERIAL"CHIP"
PACK_TYPE"0402"
TOLERANCE"1.0%"
VALUE"2"
PART_NUMBER"G21796-274"
LOCATION"R4G20";
"B"
$PN"2"24;
"A"
$PN"1"22;
%"CAP_A"
"1","(1950,3725)","0","dev_discrete","I51";
;
ROOM"MEM"
SEC"1"
SEC_TYPE"0402V"
CDS_SEC"1"
CDS_LIB"dev_discrete"
BOM_COST"SM_CONTROLLER"
CDS_LOCATION"C4G17"
MATERIAL"X7R"
VOLTAGE"25V"
PACK_TYPE"0402V"
TOLERANCE"10%"
VALUE"0.01UF"
PART_NUMBER"A36096-045"
LOCATION"C4G17";
"B"
$PN"2"7;
"A"
$PN"1"22;
%"RES"
"2","(225,2675)","2","mstr_discrete","I54";
;
CDS_SEC"1"
ROOM"MEM"
CDS_LOCATION"R6L13"
SEC"1"
SEC_TYPE"0402"
CDS_LIB"mstr_discrete"
BOM_COST"SM_CONTROLLER"
WATTAGE"1/16W"
MATERIAL"CHIP"
PACK_TYPE"0402"
TOLERANCE"1%"
VALUE"1.00K"
PART_NUMBER"G21796-026"
LOCATION"R6L13";
"A"
$PN"1"11;
"B"
$PN"2"19;
%"RES"
"2","(300,2025)","2","mstr_discrete","I56";
;
CDS_SEC"1"
ROOM"PROC"
CDS_LOCATION"R6L12"
SEC"1"
SEC_TYPE"0402"
BOM_COST"PROC_SOCKET"
CDS_LIB"mstr_discrete"
WATTAGE"1/16W"
MATERIAL"CHIP"
PACK_TYPE"0402"
TOLERANCE"1%"
VALUE"1.00K"
PART_NUMBER"G21796-026"
LOCATION"R6L12";
"A"
$PN"1"19;
"B"
$PN"2"8;
%"GND"
"1","(0,1700)","0","mstr_symbols","I57";
;
HDL_POWER"GND"
BODY_TYPE"PLUMBING"
CDS_LIB"mstr_symbols"
SIZE"1B"
VOLTAGE"0";
"A\NAC"8;
%"RES"
"1","(0,2350)","0","mstr_discrete","I58";
;
CDS_SEC"1"
ROOM"PROC"
CDS_LOCATION"R6L14"
SEC"1"
SEC_TYPE"0402"
BOM_COST"PROC_SOCKET"
CDS_LIB"mstr_discrete"
WATTAGE"1/16W"
MATERIAL"CHIP"
PACK_TYPE"0402"
TOLERANCE"1.0%"
VALUE"2"
PART_NUMBER"G21796-274"
LOCATION"R6L14";
"B"
$PN"2"19;
"A"
$PN"1"17;
%"CAP_A"
"1","(-225,2050)","0","dev_discrete","I59";
;
ROOM"MEM"
SEC"1"
SEC_TYPE"0402V"
CDS_SEC"1"
CDS_LIB"dev_discrete"
BOM_COST"SM_CONTROLLER"
CDS_LOCATION"C6L7"
MATERIAL"X7R"
VOLTAGE"25V"
PACK_TYPE"0402V"
TOLERANCE"10%"
VALUE"0.01UF"
PART_NUMBER"A36096-045"
LOCATION"C6L7";
"B"
$PN"2"8;
"A"
$PN"1"17;
%"GND"
"1","(-2025,3375)","0","mstr_symbols","I6";
;
HDL_POWER"GND"
BODY_TYPE"PLUMBING"
SIZE"1B"
CDS_LIB"mstr_symbols"
VOLTAGE"0";
"A\NAC"9;
%"RES"
"2","(2400,2650)","2","mstr_discrete","I62";
;
CDS_SEC"1"
ROOM"MEM"
CDS_LOCATION"R6L2"
SEC"1"
SEC_TYPE"0402"
CDS_LIB"mstr_discrete"
BOM_COST"SM_CONTROLLER"
WATTAGE"1/16W"
MATERIAL"CHIP"
PACK_TYPE"0402"
TOLERANCE"1%"
VALUE"1.00K"
PART_NUMBER"G21796-026"
LOCATION"R6L2";
"A"
$PN"1"12;
"B"
$PN"2"23;
%"RES"
"2","(2475,2000)","2","mstr_discrete","I64";
;
CDS_SEC"1"
ROOM"PROC"
CDS_LOCATION"R6L1"
SEC"1"
SEC_TYPE"0402"
BOM_COST"PROC_SOCKET"
CDS_LIB"mstr_discrete"
WATTAGE"1/16W"
MATERIAL"CHIP"
PACK_TYPE"0402"
TOLERANCE"1%"
VALUE"1.00K"
PART_NUMBER"G21796-026"
LOCATION"R6L1";
"A"
$PN"1"23;
"B"
$PN"2"10;
%"GND"
"1","(2175,1675)","0","mstr_symbols","I65";
;
HDL_POWER"GND"
BODY_TYPE"PLUMBING"
CDS_LIB"mstr_symbols"
SIZE"1B"
VOLTAGE"0";
"A\NAC"10;
%"RES"
"1","(2175,2325)","0","mstr_discrete","I66";
;
CDS_SEC"1"
ROOM"PROC"
CDS_LOCATION"R6L3"
SEC"1"
SEC_TYPE"0402"
BOM_COST"PROC_SOCKET"
CDS_LIB"mstr_discrete"
WATTAGE"1/16W"
MATERIAL"CHIP"
PACK_TYPE"0402"
TOLERANCE"1.0%"
VALUE"2"
PART_NUMBER"G21796-274"
LOCATION"R6L3";
"B"
$PN"2"23;
"A"
$PN"1"21;
%"CAP_A"
"1","(1950,2025)","0","dev_discrete","I67";
;
ROOM"MEM"
SEC"1"
SEC_TYPE"0402V"
CDS_SEC"1"
CDS_LIB"dev_discrete"
BOM_COST"SM_CONTROLLER"
CDS_LOCATION"C6L2"
MATERIAL"X7R"
VOLTAGE"25V"
PACK_TYPE"0402V"
TOLERANCE"10%"
VALUE"0.01UF"
PART_NUMBER"A36096-045"
LOCATION"C6L2";
"B"
$PN"2"10;
"A"
$PN"1"21;
%"PVDDQ_DEF"
"1","(225,2925)","0","mstr_symbols","I69";
;
HDL_POWER"PVDDQ_DEF"
BODY_TYPE"PLUMBING"
CDS_LIB"mstr_symbols"
VOLTAGE"1.2V";
"G\NAC"11;
%"CAP_A"
"1","(-2250,3725)","0","dev_discrete","I7";
;
ROOM"MEM"
SEC"1"
SEC_TYPE"0402V"
CDS_SEC"1"
CDS_LIB"dev_discrete"
BOM_COST"SM_CONTROLLER"
CDS_LOCATION"C4F9"
MATERIAL"X7R"
VOLTAGE"25V"
PACK_TYPE"0402V"
TOLERANCE"10%"
VALUE"0.01UF"
PART_NUMBER"A36096-045"
LOCATION"C4F9";
"B"
$PN"2"9;
"A"
$PN"1"14;
%"PVDDQ_DEF"
"1","(2400,2900)","0","mstr_symbols","I70";
;
HDL_POWER"PVDDQ_DEF"
BODY_TYPE"PLUMBING"
CDS_LIB"mstr_symbols"
VOLTAGE"1.2V";
"G\NAC"12;
%"RES"
"2","(-1800,2675)","2","mstr_discrete","I9";
;
CDS_SEC"1"
ROOM"MEM"
CDS_LOCATION"R6M1"
SEC"1"
SEC_TYPE"0402"
BOM_COST"PROC_SOCKET"
CDS_LIB"mstr_discrete"
WATTAGE"1/16W"
MATERIAL"CHIP"
PACK_TYPE"0402"
TOLERANCE"1%"
VALUE"1.00K"
PART_NUMBER"G21796-026"
LOCATION"R6M1";
"A"
$PN"1"2;
"B"
$PN"2"15;
END.
